(kicad_pcb
	(version 20260206)
	(generator "pcbnew")
	(generator_version "10.0")
	(general
		(thickness 1.6)
		(legacy_teardrops no)
	)
	(paper "A4")
	(title_block
		(title "01162023_DA0F0TEBIF0_F0T_Expander_BD_F_brd_V02_OCP.brd")
		(comment 1 "Grand Teton / footprints 3100-3105 of 9728")
	)
	(layers
		(0 "F.Cu" signal "TOP")
		(4 "In1.Cu" signal "GND")
		(6 "In2.Cu" signal "VCC")
		(8 "In3.Cu" signal "VCC1")
		(10 "In4.Cu" signal "GND1")
		(12 "In5.Cu" signal "IN1")
		(14 "In6.Cu" signal "GND2")
		(16 "In7.Cu" signal "IN2")
		(18 "In8.Cu" signal "GND3")
		(20 "In9.Cu" signal "IN3")
		(22 "In10.Cu" signal "GND4")
		(24 "In11.Cu" signal "IN4")
		(26 "In12.Cu" signal "GND5")
		(28 "In13.Cu" signal "IN5")
		(30 "In14.Cu" signal "GND6")
		(32 "In15.Cu" signal "IN6")
		(34 "In16.Cu" signal "GND7")
		(2 "B.Cu" signal "BOTTOM")
		(9 "F.Adhes" user "F.Adhesive")
		(11 "B.Adhes" user "B.Adhesive")
		(13 "F.Paste" user "Package Geometry/Pastemask Top")
		(15 "B.Paste" user "Package Geometry/Pastemask Bottom")
		(5 "F.SilkS" user "Ref Des/Silkscreen Top")
		(7 "B.SilkS" user "Ref Des/Silkscreen Bottom")
		(1 "F.Mask" user "Board Geometry/Soldermask Top")
		(3 "B.Mask" user "Board Geometry/Soldermask Bottom")
		(17 "Dwgs.User" user "User.Drawings")
		(19 "Cmts.User" user "User.Comments")
		(21 "Eco1.User" user "User.Eco1")
		(23 "Eco2.User" user "User.Eco2")
		(25 "Edge.Cuts" user "Board Geometry/Outline")
		(27 "Margin" user)
		(31 "F.CrtYd" user "Package Geometry/Place Bound Top")
		(29 "B.CrtYd" user "Package Geometry/Place Bound Bottom")
		(35 "F.Fab" user "Ref Des/Assembly Top")
		(33 "B.Fab" user "Ref Des/Assembly Bottom")
	)
	(footprint ""
		(layer "F.Cu")
		(at 417.219892 -232.979214 180)
		(property "Reference" "R6618"
			(at 0 0 180)
			(layer "F.SilkS")
			(hide yes)
			(effects
				(font
					(size 1.27 1.27)
				)
			)
		)
		(property "Value" ""
			(at 0 0 180)
			(layer "F.Fab")
			(effects
				(font
					(size 1.27 1.27)
				)
			)
		)
		(duplicate_pad_numbers_are_jumpers no)
		(fp_line
			(start 0.7874 0.4064)
			(end -0.7874 0.4064)
			(stroke
				(width 0.1524)
				(type default)
			)
			(layer "F.SilkS")
		)
		(fp_line
			(start 0.7874 -0.4064)
			(end 0.7874 0.4064)
			(stroke
				(width 0.1524)
				(type default)
			)
			(layer "F.SilkS")
		)
		(fp_line
			(start -0.7874 0.4064)
			(end -0.7874 -0.4064)
			(stroke
				(width 0.1524)
				(type default)
			)
			(layer "F.SilkS")
		)
		(fp_line
			(start -0.7874 -0.4064)
			(end 0.7874 -0.4064)
			(stroke
				(width 0.1524)
				(type default)
			)
			(layer "F.SilkS")
		)
		(fp_line
			(start 0.67945 0.3048)
			(end 0.120396 0.3048)
			(stroke
				(width 0.1)
				(type default)
			)
			(layer "F.Fab")
		)
		(fp_line
			(start 0.67945 -0.3048)
			(end 0.67945 0.3048)
			(stroke
				(width 0.1)
				(type default)
			)
			(layer "F.Fab")
		)
		(fp_line
			(start 0.12065 -0.2794)
			(end 0.12065 -0.3048)
			(stroke
				(width 0.1)
				(type default)
			)
			(layer "F.Fab")
		)
		(fp_line
			(start 0.12065 -0.3048)
			(end 0.67945 -0.3048)
			(stroke
				(width 0.1)
				(type default)
			)
			(layer "F.Fab")
		)
		(fp_line
			(start 0.120396 0.3048)
			(end 0.120396 0.2794)
			(stroke
				(width 0.1)
				(type default)
			)
			(layer "F.Fab")
		)
		(fp_line
			(start 0.120396 0.2794)
			(end -0.12065 0.2794)
			(stroke
				(width 0.1)
				(type default)
			)
			(layer "F.Fab")
		)
		(fp_line
			(start -0.12065 0.3048)
			(end -0.67945 0.3048)
			(stroke
				(width 0.1)
				(type default)
			)
			(layer "F.Fab")
		)
		(fp_line
			(start -0.12065 0.2794)
			(end -0.12065 0.3048)
			(stroke
				(width 0.1)
				(type default)
			)
			(layer "F.Fab")
		)
		(fp_line
			(start -0.12065 -0.2794)
			(end 0.12065 -0.2794)
			(stroke
				(width 0.1)
				(type default)
			)
			(layer "F.Fab")
		)
		(fp_line
			(start -0.12065 -0.305054)
			(end -0.12065 -0.2794)
			(stroke
				(width 0.1)
				(type default)
			)
			(layer "F.Fab")
		)
		(fp_line
			(start -0.67945 0.3048)
			(end -0.67945 -0.305054)
			(stroke
				(width 0.1)
				(type default)
			)
			(layer "F.Fab")
		)
		(fp_line
			(start -0.67945 -0.305054)
			(end -0.12065 -0.305054)
			(stroke
				(width 0.1)
				(type default)
			)
			(layer "F.Fab")
		)
		(pad "1" smd circle
			(at -0.40005 0 180)
			(size 0 0)
			(layers "F.Cu" "F.Mask" "F.Paste")
			(net "UART_PEX3_SDB_BUF_R_TX")
		)
		(pad "2" smd circle
			(at 0.40005 0 180)
			(size 0 0)
			(layers "F.Cu" "F.Mask" "F.Paste")
			(net "UART_PEX3_SDB_BUF_R1_TX")
		)
	)
	(footprint ""
		(layer "F.Cu")
		(at 123.975114 -252.416564 90)
		(property "Reference" "R829"
			(at 0 0 90)
			(layer "F.SilkS")
			(hide yes)
			(effects
				(font
					(size 1.27 1.27)
				)
			)
		)
		(property "Value" ""
			(at 0 0 90)
			(layer "F.Fab")
			(effects
				(font
					(size 1.27 1.27)
				)
			)
		)
		(duplicate_pad_numbers_are_jumpers no)
		(fp_line
			(start 0.7874 -0.4064)
			(end 0.7874 0.4064)
			(stroke
				(width 0.1524)
				(type default)
			)
			(layer "F.SilkS")
		)
		(fp_line
			(start -0.7874 -0.4064)
			(end 0.7874 -0.4064)
			(stroke
				(width 0.1524)
				(type default)
			)
			(layer "F.SilkS")
		)
		(fp_line
			(start 0.7874 0.4064)
			(end -0.7874 0.4064)
			(stroke
				(width 0.1524)
				(type default)
			)
			(layer "F.SilkS")
		)
		(fp_line
			(start -0.7874 0.4064)
			(end -0.7874 -0.4064)
			(stroke
				(width 0.1524)
				(type default)
			)
			(layer "F.SilkS")
		)
		(fp_line
			(start -0.12065 -0.305054)
			(end -0.12065 -0.2794)
			(stroke
				(width 0.1)
				(type default)
			)
			(layer "F.Fab")
		)
		(fp_line
			(start -0.67945 -0.305054)
			(end -0.12065 -0.305054)
			(stroke
				(width 0.1)
				(type default)
			)
			(layer "F.Fab")
		)
		(fp_line
			(start 0.67945 -0.3048)
			(end 0.67945 0.3048)
			(stroke
				(width 0.1)
				(type default)
			)
			(layer "F.Fab")
		)
		(fp_line
			(start 0.12065 -0.3048)
			(end 0.67945 -0.3048)
			(stroke
				(width 0.1)
				(type default)
			)
			(layer "F.Fab")
		)
		(fp_line
			(start 0.12065 -0.2794)
			(end 0.12065 -0.3048)
			(stroke
				(width 0.1)
				(type default)
			)
			(layer "F.Fab")
		)
		(fp_line
			(start -0.12065 -0.2794)
			(end 0.12065 -0.2794)
			(stroke
				(width 0.1)
				(type default)
			)
			(layer "F.Fab")
		)
		(fp_line
			(start 0.120396 0.2794)
			(end -0.12065 0.2794)
			(stroke
				(width 0.1)
				(type default)
			)
			(layer "F.Fab")
		)
		(fp_line
			(start -0.12065 0.2794)
			(end -0.12065 0.3048)
			(stroke
				(width 0.1)
				(type default)
			)
			(layer "F.Fab")
		)
		(fp_line
			(start 0.67945 0.3048)
			(end 0.120396 0.3048)
			(stroke
				(width 0.1)
				(type default)
			)
			(layer "F.Fab")
		)
		(fp_line
			(start 0.120396 0.3048)
			(end 0.120396 0.2794)
			(stroke
				(width 0.1)
				(type default)
			)
			(layer "F.Fab")
		)
		(fp_line
			(start -0.12065 0.3048)
			(end -0.67945 0.3048)
			(stroke
				(width 0.1)
				(type default)
			)
			(layer "F.Fab")
		)
		(fp_line
			(start -0.67945 0.3048)
			(end -0.67945 -0.305054)
			(stroke
				(width 0.1)
				(type default)
			)
			(layer "F.Fab")
		)
		(pad "1" smd circle
			(at -0.40005 0 90)
			(size 0 0)
			(layers "F.Cu" "F.Mask" "F.Paste")
			(net "SMB_BIC_I2C6_MUX_VR_R_SDA")
		)
		(pad "2" smd circle
			(at 0.40005 0 90)
			(size 0 0)
			(layers "F.Cu" "F.Mask" "F.Paste")
			(net "SMB_VR_P0V8_PEX0_SDA")
		)
	)
	(footprint ""
		(layer "F.Cu")
		(at 336.042 -158.75)
		(property "Reference" "R4787"
			(at 0 0 0)
			(layer "F.SilkS")
			(hide yes)
			(effects
				(font
					(size 1.27 1.27)
				)
			)
		)
		(property "Value" ""
			(at 0 0 0)
			(layer "F.Fab")
			(effects
				(font
					(size 1.27 1.27)
				)
			)
		)
		(duplicate_pad_numbers_are_jumpers no)
		(fp_line
			(start -0.7874 -0.4064)
			(end 0.7874 -0.4064)
			(stroke
				(width 0.1524)
				(type default)
			)
			(layer "F.SilkS")
		)
		(fp_line
			(start -0.7874 0.4064)
			(end -0.7874 -0.4064)
			(stroke
				(width 0.1524)
				(type default)
			)
			(layer "F.SilkS")
		)
		(fp_line
			(start 0.7874 -0.4064)
			(end 0.7874 0.4064)
			(stroke
				(width 0.1524)
				(type default)
			)
			(layer "F.SilkS")
		)
		(fp_line
			(start 0.7874 0.4064)
			(end -0.7874 0.4064)
			(stroke
				(width 0.1524)
				(type default)
			)
			(layer "F.SilkS")
		)
		(fp_line
			(start -0.67945 -0.305054)
			(end -0.12065 -0.305054)
			(stroke
				(width 0.1)
				(type default)
			)
			(layer "F.Fab")
		)
		(fp_line
			(start -0.67945 0.3048)
			(end -0.67945 -0.305054)
			(stroke
				(width 0.1)
				(type default)
			)
			(layer "F.Fab")
		)
		(fp_line
			(start -0.12065 -0.305054)
			(end -0.12065 -0.2794)
			(stroke
				(width 0.1)
				(type default)
			)
			(layer "F.Fab")
		)
		(fp_line
			(start -0.12065 -0.2794)
			(end 0.12065 -0.2794)
			(stroke
				(width 0.1)
				(type default)
			)
			(layer "F.Fab")
		)
		(fp_line
			(start -0.12065 0.2794)
			(end -0.12065 0.3048)
			(stroke
				(width 0.1)
				(type default)
			)
			(layer "F.Fab")
		)
		(fp_line
			(start -0.12065 0.3048)
			(end -0.67945 0.3048)
			(stroke
				(width 0.1)
				(type default)
			)
			(layer "F.Fab")
		)
		(fp_line
			(start 0.120396 0.2794)
			(end -0.12065 0.2794)
			(stroke
				(width 0.1)
				(type default)
			)
			(layer "F.Fab")
		)
		(fp_line
			(start 0.120396 0.3048)
			(end 0.120396 0.2794)
			(stroke
				(width 0.1)
				(type default)
			)
			(layer "F.Fab")
		)
		(fp_line
			(start 0.12065 -0.3048)
			(end 0.67945 -0.3048)
			(stroke
				(width 0.1)
				(type default)
			)
			(layer "F.Fab")
		)
		(fp_line
			(start 0.12065 -0.2794)
			(end 0.12065 -0.3048)
			(stroke
				(width 0.1)
				(type default)
			)
			(layer "F.Fab")
		)
		(fp_line
			(start 0.67945 -0.3048)
			(end 0.67945 0.3048)
			(stroke
				(width 0.1)
				(type default)
			)
			(layer "F.Fab")
		)
		(fp_line
			(start 0.67945 0.3048)
			(end 0.120396 0.3048)
			(stroke
				(width 0.1)
				(type default)
			)
			(layer "F.Fab")
		)
		(pad "1" smd circle
			(at -0.40005 0)
			(size 0 0)
			(layers "F.Cu" "F.Mask" "F.Paste")
			(net "P3V3_AUX")
		)
		(pad "2" smd circle
			(at 0.40005 0)
			(size 0 0)
			(layers "F.Cu" "F.Mask" "F.Paste")
			(net "SSD12_PEX_PWR_EN_R")
		)
	)
	(footprint ""
		(layer "F.Cu")
		(at 361.188 -185.166 180)
		(property "Reference" "R4647"
			(at 0 0 180)
			(layer "F.SilkS")
			(hide yes)
			(effects
				(font
					(size 1.27 1.27)
				)
			)
		)
		(property "Value" ""
			(at 0 0 180)
			(layer "F.Fab")
			(effects
				(font
					(size 1.27 1.27)
				)
			)
		)
		(duplicate_pad_numbers_are_jumpers no)
		(fp_line
			(start 0.7874 0.4064)
			(end -0.7874 0.4064)
			(stroke
				(width 0.1524)
				(type default)
			)
			(layer "F.SilkS")
		)
		(fp_line
			(start 0.7874 -0.4064)
			(end 0.7874 0.4064)
			(stroke
				(width 0.1524)
				(type default)
			)
			(layer "F.SilkS")
		)
		(fp_line
			(start -0.7874 0.4064)
			(end -0.7874 -0.4064)
			(stroke
				(width 0.1524)
				(type default)
			)
			(layer "F.SilkS")
		)
		(fp_line
			(start -0.7874 -0.4064)
			(end 0.7874 -0.4064)
			(stroke
				(width 0.1524)
				(type default)
			)
			(layer "F.SilkS")
		)
		(fp_line
			(start 0.67945 0.3048)
			(end 0.120396 0.3048)
			(stroke
				(width 0.1)
				(type default)
			)
			(layer "F.Fab")
		)
		(fp_line
			(start 0.67945 -0.3048)
			(end 0.67945 0.3048)
			(stroke
				(width 0.1)
				(type default)
			)
			(layer "F.Fab")
		)
		(fp_line
			(start 0.12065 -0.2794)
			(end 0.12065 -0.3048)
			(stroke
				(width 0.1)
				(type default)
			)
			(layer "F.Fab")
		)
		(fp_line
			(start 0.12065 -0.3048)
			(end 0.67945 -0.3048)
			(stroke
				(width 0.1)
				(type default)
			)
			(layer "F.Fab")
		)
		(fp_line
			(start 0.120396 0.3048)
			(end 0.120396 0.2794)
			(stroke
				(width 0.1)
				(type default)
			)
			(layer "F.Fab")
		)
		(fp_line
			(start 0.120396 0.2794)
			(end -0.12065 0.2794)
			(stroke
				(width 0.1)
				(type default)
			)
			(layer "F.Fab")
		)
		(fp_line
			(start -0.12065 0.3048)
			(end -0.67945 0.3048)
			(stroke
				(width 0.1)
				(type default)
			)
			(layer "F.Fab")
		)
		(fp_line
			(start -0.12065 0.2794)
			(end -0.12065 0.3048)
			(stroke
				(width 0.1)
				(type default)
			)
			(layer "F.Fab")
		)
		(fp_line
			(start -0.12065 -0.2794)
			(end 0.12065 -0.2794)
			(stroke
				(width 0.1)
				(type default)
			)
			(layer "F.Fab")
		)
		(fp_line
			(start -0.12065 -0.305054)
			(end -0.12065 -0.2794)
			(stroke
				(width 0.1)
				(type default)
			)
			(layer "F.Fab")
		)
		(fp_line
			(start -0.67945 0.3048)
			(end -0.67945 -0.305054)
			(stroke
				(width 0.1)
				(type default)
			)
			(layer "F.Fab")
		)
		(fp_line
			(start -0.67945 -0.305054)
			(end -0.12065 -0.305054)
			(stroke
				(width 0.1)
				(type default)
			)
			(layer "F.Fab")
		)
		(pad "1" smd circle
			(at -0.40005 0 180)
			(size 0 0)
			(layers "F.Cu" "F.Mask" "F.Paste")
			(net "SSD3_PEX_PWR_EN")
		)
		(pad "2" smd circle
			(at 0.40005 0 180)
			(size 0 0)
			(layers "F.Cu" "F.Mask" "F.Paste")
			(net "SSD3_PEX_PWR_EN_R")
		)
	)
	(footprint ""
		(layer "F.Cu")
		(at 310.443626 -44.87291)
		(property "Reference" "R617"
			(at 0 0 0)
			(layer "F.SilkS")
			(hide yes)
			(effects
				(font
					(size 1.27 1.27)
				)
			)
		)
		(property "Value" ""
			(at 0 0 0)
			(layer "F.Fab")
			(effects
				(font
					(size 1.27 1.27)
				)
			)
		)
		(duplicate_pad_numbers_are_jumpers no)
		(fp_line
			(start -0.7874 -0.4064)
			(end 0.7874 -0.4064)
			(stroke
				(width 0.1524)
				(type default)
			)
			(layer "F.SilkS")
		)
		(fp_line
			(start -0.7874 0.4064)
			(end -0.7874 -0.4064)
			(stroke
				(width 0.1524)
				(type default)
			)
			(layer "F.SilkS")
		)
		(fp_line
			(start 0.7874 -0.4064)
			(end 0.7874 0.4064)
			(stroke
				(width 0.1524)
				(type default)
			)
			(layer "F.SilkS")
		)
		(fp_line
			(start 0.7874 0.4064)
			(end -0.7874 0.4064)
			(stroke
				(width 0.1524)
				(type default)
			)
			(layer "F.SilkS")
		)
		(fp_line
			(start -0.67945 -0.305054)
			(end -0.12065 -0.305054)
			(stroke
				(width 0.1)
				(type default)
			)
			(layer "F.Fab")
		)
		(fp_line
			(start -0.67945 0.3048)
			(end -0.67945 -0.305054)
			(stroke
				(width 0.1)
				(type default)
			)
			(layer "F.Fab")
		)
		(fp_line
			(start -0.12065 -0.305054)
			(end -0.12065 -0.2794)
			(stroke
				(width 0.1)
				(type default)
			)
			(layer "F.Fab")
		)
		(fp_line
			(start -0.12065 -0.2794)
			(end 0.12065 -0.2794)
			(stroke
				(width 0.1)
				(type default)
			)
			(layer "F.Fab")
		)
		(fp_line
			(start -0.12065 0.2794)
			(end -0.12065 0.3048)
			(stroke
				(width 0.1)
				(type default)
			)
			(layer "F.Fab")
		)
		(fp_line
			(start -0.12065 0.3048)
			(end -0.67945 0.3048)
			(stroke
				(width 0.1)
				(type default)
			)
			(layer "F.Fab")
		)
		(fp_line
			(start 0.120396 0.2794)
			(end -0.12065 0.2794)
			(stroke
				(width 0.1)
				(type default)
			)
			(layer "F.Fab")
		)
		(fp_line
			(start 0.120396 0.3048)
			(end 0.120396 0.2794)
			(stroke
				(width 0.1)
				(type default)
			)
			(layer "F.Fab")
		)
		(fp_line
			(start 0.12065 -0.3048)
			(end 0.67945 -0.3048)
			(stroke
				(width 0.1)
				(type default)
			)
			(layer "F.Fab")
		)
		(fp_line
			(start 0.12065 -0.2794)
			(end 0.12065 -0.3048)
			(stroke
				(width 0.1)
				(type default)
			)
			(layer "F.Fab")
		)
		(fp_line
			(start 0.67945 -0.3048)
			(end 0.67945 0.3048)
			(stroke
				(width 0.1)
				(type default)
			)
			(layer "F.Fab")
		)
		(fp_line
			(start 0.67945 0.3048)
			(end 0.120396 0.3048)
			(stroke
				(width 0.1)
				(type default)
			)
			(layer "F.Fab")
		)
		(pad "1" smd circle
			(at -0.40005 0)
			(size 0 0)
			(layers "F.Cu" "F.Mask" "F.Paste")
			(net "SSD10_ADC_A0")
		)
		(pad "2" smd circle
			(at 0.40005 0)
			(size 0 0)
			(layers "F.Cu" "F.Mask" "F.Paste")
			(net "P3V3_AUX")
		)
	)
	(footprint ""
		(layer "F.Cu")
		(at 226.19716 -266.794996)
		(property "Reference" "L100"
			(at 0 0 0)
			(layer "F.SilkS")
			(hide yes)
			(effects
				(font
					(size 1.27 1.27)
				)
			)
		)
		(property "Value" ""
			(at 0 0 0)
			(layer "F.Fab")
			(effects
				(font
					(size 1.27 1.27)
				)
			)
		)
		(duplicate_pad_numbers_are_jumpers no)
		(fp_line
			(start -2.248154 -4.9911)
			(end -2.248154 -1.761236)
			(stroke
				(width 0.1524)
				(type default)
			)
			(layer "F.SilkS")
		)
		(fp_line
			(start -2.248154 1.62052)
			(end -2.248154 4.9911)
			(stroke
				(width 0.1524)
				(type default)
			)
			(layer "F.SilkS")
		)
		(fp_line
			(start -2.248154 4.9911)
			(end 2.248154 4.9911)
			(stroke
				(width 0.1524)
				(type default)
			)
			(layer "F.SilkS")
		)
		(fp_line
			(start 2.248154 -4.9911)
			(end -2.248154 -4.9911)
			(stroke
				(width 0.1524)
				(type default)
			)
			(layer "F.SilkS")
		)
		(fp_line
			(start 2.248154 -1.783334)
			(end 2.248154 -4.9911)
			(stroke
				(width 0.1524)
				(type default)
			)
			(layer "F.SilkS")
		)
		(fp_line
			(start 2.248154 4.9911)
			(end 2.248154 1.477518)
			(stroke
				(width 0.1524)
				(type default)
			)
			(layer "F.SilkS")
		)
		(fp_line
			(start -1.700022 -0.899922)
			(end -1.700022 0.899922)
			(stroke
				(width 0.1)
				(type default)
			)
			(layer "F.Fab")
		)
		(fp_line
			(start -1.700022 0.899922)
			(end 1.700022 0.899922)
			(stroke
				(width 0.1)
				(type default)
			)
			(layer "F.Fab")
		)
		(fp_line
			(start 1.700022 -0.899922)
			(end -1.700022 -0.899922)
			(stroke
				(width 0.1)
				(type default)
			)
			(layer "F.Fab")
		)
		(fp_line
			(start 1.700022 0.899922)
			(end 1.700022 -0.899922)
			(stroke
				(width 0.1)
				(type default)
			)
			(layer "F.Fab")
		)
		(pad "1" smd rect
			(at -1.575054 0)
			(size 1.1684 9.8044)
			(layers "F.Cu" "F.Mask" "F.Paste")
			(net "P1V25_PEX1")
		)
		(pad "2" smd rect
			(at 1.575054 0)
			(size 1.1684 9.8044)
			(layers "F.Cu" "F.Mask" "F.Paste")
			(net "P1V25_SERDES_VDDPLL_PEX1")
		)
	)
)
